# T6G (Grand Teton) — schematic netlist excerpt (pin names and nets, part order shuffled) for the footprints in the layout excerpt that follows; sources: Cadence DE-HDL packaged netlist, KiCad conversion of 04192023_DAF0TMB3IC0_F0TG_MB_C_brd_V02_OCP.brd

PC566  Q_CAPP  270UF 16V 20% OSCON  pkg THLF  page 190 : A = SW_P3V3_AUX_FLT ; B = GND
PR6624  Q_RES  1.5 1% EMPTY  pkg 0402LF  page 365 : A = SW_P0V9_RETIMER_CPU1_SW1_RC ; B = GND
R906  Q_RES  20K 1% CHIP  pkg 0201LF  page 353 : A = RT_CPU1_P3_ADDR2 ; B = GND
C6088  Q_CAP  10UF 16V 10% X6S  pkg C0805  page 178 : A = USB_HUB2_MRP_RESET_N ; B = GND

(kicad_pcb
	(version 20260206)
	(generator "pcbnew")
	(generator_version "10.0")
	(general
		(thickness 1.6)
		(legacy_teardrops no)
	)
	(paper "A4")
	(title_block
		(title "04192023_DAF0TMB3IC0_F0TG_MB_C_brd_V02_OCP.brd")
		(comment 1 "Grand Teton / footprints 3995-3998 of 8354")
	)
	(layers
		(0 "F.Cu" signal "TOP")
		(4 "In1.Cu" signal "GND")
		(6 "In2.Cu" signal "IN1")
		(8 "In3.Cu" signal "GND1")
		(10 "In4.Cu" signal "IN2")
		(12 "In5.Cu" signal "GND2")
		(14 "In6.Cu" signal "IN3")
		(16 "In7.Cu" signal "GND3")
		(18 "In8.Cu" signal "VCC")
		(20 "In9.Cu" signal "VCC1")
		(22 "In10.Cu" signal "GND4")
		(24 "In11.Cu" signal "IN4")
		(26 "In12.Cu" signal "GND5")
		(28 "In13.Cu" signal "IN5")
		(30 "In14.Cu" signal "GND6")
		(32 "In15.Cu" signal "IN6")
		(34 "In16.Cu" signal "GND7")
		(2 "B.Cu" signal "BOTTOM")
		(9 "F.Adhes" user "F.Adhesive")
		(11 "B.Adhes" user "B.Adhesive")
		(13 "F.Paste" user "Package Geometry/Pastemask Top")
		(15 "B.Paste" user "Package Geometry/Pastemask Bottom")
		(5 "F.SilkS" user "Ref Des/Silkscreen Top")
		(7 "B.SilkS" user "Ref Des/Silkscreen Bottom")
		(1 "F.Mask" user "Board Geometry/Soldermask Top")
		(3 "B.Mask" user "Board Geometry/Soldermask Bottom")
		(17 "Dwgs.User" user "User.Drawings")
		(19 "Cmts.User" user "User.Comments")
		(21 "Eco1.User" user "User.Eco1")
		(23 "Eco2.User" user "User.Eco2")
		(25 "Edge.Cuts" user "Board Geometry/Outline")
		(27 "Margin" user)
		(31 "F.CrtYd" user "Package Geometry/Place Bound Top")
		(29 "B.CrtYd" user "Package Geometry/Place Bound Bottom")
		(35 "F.Fab" user "Ref Des/Assembly Top")
		(33 "B.Fab" user "Ref Des/Assembly Bottom")
	)
	(footprint ""
		(layer "F.Cu")
		(at 12.360148 -387.30809 90)
		(property "Reference" "PR6624"
			(at 0 0 90)
			(layer "F.SilkS")
			(hide yes)
			(effects
				(font
					(size 1.27 1.27)
				)
			)
		)
		(property "Value" ""
			(at 0 0 90)
			(layer "F.Fab")
			(effects
				(font
					(size 1.27 1.27)
				)
			)
		)
		(duplicate_pad_numbers_are_jumpers no)
		(fp_line
			(start 0.7874 -0.4064)
			(end 0.7874 0.4064)
			(stroke
				(width 0.1524)
				(type default)
			)
			(layer "F.SilkS")
		)
		(fp_line
			(start -0.7874 -0.4064)
			(end 0.7874 -0.4064)
			(stroke
				(width 0.1524)
				(type default)
			)
			(layer "F.SilkS")
		)
		(fp_line
			(start 0.7874 0.4064)
			(end -0.7874 0.4064)
			(stroke
				(width 0.1524)
				(type default)
			)
			(layer "F.SilkS")
		)
		(fp_line
			(start -0.7874 0.4064)
			(end -0.7874 -0.4064)
			(stroke
				(width 0.1524)
				(type default)
			)
			(layer "F.SilkS")
		)
		(fp_line
			(start -0.12065 -0.305054)
			(end -0.12065 -0.2794)
			(stroke
				(width 0.1)
				(type default)
			)
			(layer "F.Fab")
		)
		(fp_line
			(start -0.67945 -0.305054)
			(end -0.12065 -0.305054)
			(stroke
				(width 0.1)
				(type default)
			)
			(layer "F.Fab")
		)
		(fp_line
			(start 0.67945 -0.3048)
			(end 0.67945 0.3048)
			(stroke
				(width 0.1)
				(type default)
			)
			(layer "F.Fab")
		)
		(fp_line
			(start 0.12065 -0.3048)
			(end 0.67945 -0.3048)
			(stroke
				(width 0.1)
				(type default)
			)
			(layer "F.Fab")
		)
		(fp_line
			(start 0.12065 -0.2794)
			(end 0.12065 -0.3048)
			(stroke
				(width 0.1)
				(type default)
			)
			(layer "F.Fab")
		)
		(fp_line
			(start -0.12065 -0.2794)
			(end 0.12065 -0.2794)
			(stroke
				(width 0.1)
				(type default)
			)
			(layer "F.Fab")
		)
		(fp_line
			(start 0.120396 0.2794)
			(end -0.12065 0.2794)
			(stroke
				(width 0.1)
				(type default)
			)
			(layer "F.Fab")
		)
		(fp_line
			(start -0.12065 0.2794)
			(end -0.12065 0.3048)
			(stroke
				(width 0.1)
				(type default)
			)
			(layer "F.Fab")
		)
		(fp_line
			(start 0.67945 0.3048)
			(end 0.120396 0.3048)
			(stroke
				(width 0.1)
				(type default)
			)
			(layer "F.Fab")
		)
		(fp_line
			(start 0.120396 0.3048)
			(end 0.120396 0.2794)
			(stroke
				(width 0.1)
				(type default)
			)
			(layer "F.Fab")
		)
		(fp_line
			(start -0.12065 0.3048)
			(end -0.67945 0.3048)
			(stroke
				(width 0.1)
				(type default)
			)
			(layer "F.Fab")
		)
		(fp_line
			(start -0.67945 0.3048)
			(end -0.67945 -0.305054)
			(stroke
				(width 0.1)
				(type default)
			)
			(layer "F.Fab")
		)
		(pad "1" smd circle
			(at -0.40005 0 90)
			(size 0 0)
			(layers "F.Cu" "F.Mask" "F.Paste")
			(net "SW_P0V9_RETIMER_CPU1_SW1_RC")
		)
		(pad "2" smd circle
			(at 0.40005 0 90)
			(size 0 0)
			(layers "F.Cu" "F.Mask" "F.Paste")
			(net "GND")
		)
	)
	(footprint ""
		(layer "F.Cu")
		(at 139.794742 -386.7912 90)
		(property "Reference" "R906"
			(at 0 0 90)
			(layer "F.SilkS")
			(hide yes)
			(effects
				(font
					(size 1.27 1.27)
				)
			)
		)
		(property "Value" ""
			(at 0 0 90)
			(layer "F.Fab")
			(effects
				(font
					(size 1.27 1.27)
				)
			)
		)
		(duplicate_pad_numbers_are_jumpers no)
		(fp_line
			(start 0.32512 -0.175006)
			(end 0.32512 0.175006)
			(stroke
				(width 0.1)
				(type default)
			)
			(layer "F.Fab")
		)
		(fp_line
			(start -0.32512 -0.175006)
			(end 0.32512 -0.175006)
			(stroke
				(width 0.1)
				(type default)
			)
			(layer "F.Fab")
		)
		(fp_line
			(start 0.32512 0.175006)
			(end -0.32512 0.175006)
			(stroke
				(width 0.1)
				(type default)
			)
			(layer "F.Fab")
		)
		(fp_line
			(start -0.32512 0.175006)
			(end -0.32512 -0.175006)
			(stroke
				(width 0.1)
				(type default)
			)
			(layer "F.Fab")
		)
		(pad "1" smd rect
			(at -0.2667 0 90)
			(size 0.3048 0.381)
			(layers "F.Cu" "F.Mask" "F.Paste")
			(net "RT_CPU1_P3_ADDR2")
		)
		(pad "2" smd rect
			(at 0.2667 0 270)
			(size 0.3048 0.381)
			(layers "F.Cu" "F.Mask" "F.Paste")
			(net "GND")
		)
	)
	(footprint ""
		(layer "F.Cu")
		(at 99.606862 -54.15153 90)
		(property "Reference" "C6088"
			(at 0 0 90)
			(layer "F.SilkS")
			(hide yes)
			(effects
				(font
					(size 1.27 1.27)
				)
			)
		)
		(property "Value" ""
			(at 0 0 90)
			(layer "F.Fab")
			(effects
				(font
					(size 1.27 1.27)
				)
			)
		)
		(duplicate_pad_numbers_are_jumpers no)
		(fp_line
			(start 1.524 -0.762)
			(end 1.524 0.762)
			(stroke
				(width 0.1524)
				(type default)
			)
			(layer "F.SilkS")
		)
		(fp_line
			(start -1.524 -0.762)
			(end 1.524 -0.762)
			(stroke
				(width 0.1524)
				(type default)
			)
			(layer "F.SilkS")
		)
		(fp_line
			(start 1.524 0.762)
			(end -1.524 0.762)
			(stroke
				(width 0.1524)
				(type default)
			)
			(layer "F.SilkS")
		)
		(fp_line
			(start -1.524 0.762)
			(end -1.524 -0.762)
			(stroke
				(width 0.1524)
				(type default)
			)
			(layer "F.SilkS")
		)
		(fp_line
			(start 1.1049 -0.724916)
			(end -1.1049 -0.724916)
			(stroke
				(width 0.1)
				(type default)
			)
			(layer "F.Fab")
		)
		(fp_line
			(start -1.1049 -0.724916)
			(end -1.1049 0.724916)
			(stroke
				(width 0.1)
				(type default)
			)
			(layer "F.Fab")
		)
		(fp_line
			(start 1.1049 0.724916)
			(end 1.1049 -0.724916)
			(stroke
				(width 0.1)
				(type default)
			)
			(layer "F.Fab")
		)
		(fp_line
			(start -1.1049 0.724916)
			(end 1.1049 0.724916)
			(stroke
				(width 0.1)
				(type default)
			)
			(layer "F.Fab")
		)
		(pad "1" smd rect
			(at -0.889 0 270)
			(size 1.016 1.27)
			(layers "F.Cu" "F.Mask" "F.Paste")
			(net "USB_HUB2_MRP_RESET_N")
		)
		(pad "2" smd rect
			(at 0.889 0 270)
			(size 1.016 1.27)
			(layers "F.Cu" "F.Mask" "F.Paste")
			(net "GND")
		)
	)
	(footprint ""
		(layer "F.Cu")
		(at 439.84164 -50.447448 180)
		(property "Reference" "PC566"
			(at 0.46228 -3.198368 0)
			(unlocked yes)
			(layer "F.SilkS")
			(effects
				(font
					(size 0.7874 0.5842)
					(thickness 0.1524)
				)
				(justify left)
			)
		)
		(property "Value" ""
			(at 0 0 180)
			(layer "F.Fab")
			(effects
				(font
					(size 1.27 1.27)
				)
			)
		)
		(duplicate_pad_numbers_are_jumpers no)
		(fp_line
			(start -3.400044 1.249934)
			(end 3.400044 1.249934)
			(stroke
				(width 0.1524)
				(type default)
			)
			(layer "F.SilkS")
		)
		(fp_circle
			(center 0 1.249934)
			(end -3.39979 1.249934)
			(stroke
				(width 0.1524)
				(type default)
			)
			(fill no)
			(layer "F.SilkS")
		)
		(fp_poly
			(pts
				(arc
					(start 3.400044 1.249934)
					(mid 0 4.649978)
					(end -3.400044 1.249934)
				)
			)
			(stroke
				(width 0)
				(type default)
			)
			(fill yes)
			(layer "F.SilkS")
		)
		(fp_circle
			(center 0 1.249934)
			(end -3.39979 1.249934)
			(stroke
				(width 0.1)
				(type default)
			)
			(fill no)
			(layer "F.Fab")
		)
		(pad "1" thru_hole rect
			(at 0 0 180)
			(size 1.524 1.524)
			(drill 1.016)
			(layers "*.Cu" "*.Mask")
			(remove_unused_layers no)
			(net "SW_P3V3_AUX_FLT")
			(clearance 0)
			(padstack
				(mode front_inner_back)
				(layer "Inner"
					(shape circle)
					(size 1.524 1.524)
					(clearance 0)
				)
				(layer "B.Cu"
					(shape rect)
					(size 1.524 1.524)
					(clearance 0)
				)
			)
		)
		(pad "2" thru_hole circle
			(at 0 2.500122 180)
			(size 1.524 1.524)
			(drill 1.016)
			(layers "*.Cu" "*.Mask")
			(remove_unused_layers no)
			(net "GND")
			(clearance 0)
		)
	)
)
